# T6G (Grand Teton) — schematic netlist excerpt (pin names and nets, part order shuffled) for the footprints in the layout excerpt that follows; sources: Cadence DE-HDL packaged netlist, KiCad conversion of 04192023_DAF0TMB3IC0_F0TG_MB_C_brd_V02_OCP.brd

R6003  Q_RES  0 5% CHIP  pkg 0402LF  page 150 : A = I3C_SCM_1_SDA ; B = I3C_SCM_1_R_SDA
C164  Q_CAP  0.1UF 25V 10% X7R  pkg 0402  page 105 : A = P3V3_AUX ; B = GND
PC430_5  Q_CAP  22UF 4V 20% X6S  pkg C0805  page 220 : A = PVDDCR_CPU1_P1 ; B = GND

(kicad_pcb
	(version 20260206)
	(generator "pcbnew")
	(generator_version "10.0")
	(general
		(thickness 1.6)
		(legacy_teardrops no)
	)
	(paper "A4")
	(title_block
		(title "04192023_DAF0TMB3IC0_F0TG_MB_C_brd_V02_OCP.brd")
		(comment 1 "Grand Teton / footprints 8119-8121 of 8354")
	)
	(layers
		(0 "F.Cu" signal "TOP")
		(4 "In1.Cu" signal "GND")
		(6 "In2.Cu" signal "IN1")
		(8 "In3.Cu" signal "GND1")
		(10 "In4.Cu" signal "IN2")
		(12 "In5.Cu" signal "GND2")
		(14 "In6.Cu" signal "IN3")
		(16 "In7.Cu" signal "GND3")
		(18 "In8.Cu" signal "VCC")
		(20 "In9.Cu" signal "VCC1")
		(22 "In10.Cu" signal "GND4")
		(24 "In11.Cu" signal "IN4")
		(26 "In12.Cu" signal "GND5")
		(28 "In13.Cu" signal "IN5")
		(30 "In14.Cu" signal "GND6")
		(32 "In15.Cu" signal "IN6")
		(34 "In16.Cu" signal "GND7")
		(2 "B.Cu" signal "BOTTOM")
		(9 "F.Adhes" user "F.Adhesive")
		(11 "B.Adhes" user "B.Adhesive")
		(13 "F.Paste" user "Package Geometry/Pastemask Top")
		(15 "B.Paste" user "Package Geometry/Pastemask Bottom")
		(5 "F.SilkS" user "Ref Des/Silkscreen Top")
		(7 "B.SilkS" user "Ref Des/Silkscreen Bottom")
		(1 "F.Mask" user "Board Geometry/Soldermask Top")
		(3 "B.Mask" user "Board Geometry/Soldermask Bottom")
		(17 "Dwgs.User" user "User.Drawings")
		(19 "Cmts.User" user "User.Comments")
		(21 "Eco1.User" user "User.Eco1")
		(23 "Eco2.User" user "User.Eco2")
		(25 "Edge.Cuts" user "Board Geometry/Outline")
		(27 "Margin" user)
		(31 "F.CrtYd" user "Package Geometry/Place Bound Top")
		(29 "B.CrtYd" user "Package Geometry/Place Bound Bottom")
		(35 "F.Fab" user "Ref Des/Assembly Top")
		(33 "B.Fab" user "Ref Des/Assembly Bottom")
	)
	(footprint ""
		(layer "B.Cu")
		(at 175.316388 -193.996564)
		(property "Reference" "C164"
			(at 0 0 0)
			(layer "B.SilkS")
			(hide yes)
			(effects
				(font
					(size 1.27 1.27)
				)
				(justify mirror)
			)
		)
		(property "Value" ""
			(at 0 0 0)
			(layer "B.Fab")
			(effects
				(font
					(size 1.27 1.27)
				)
				(justify mirror)
			)
		)
		(duplicate_pad_numbers_are_jumpers no)
		(fp_line
			(start -0.7874 -0.4064)
			(end -0.7874 0.4064)
			(stroke
				(width 0.1524)
				(type default)
			)
			(layer "B.SilkS")
		)
		(fp_line
			(start -0.7874 0.4064)
			(end 0.7874 0.4064)
			(stroke
				(width 0.1524)
				(type default)
			)
			(layer "B.SilkS")
		)
		(fp_line
			(start 0.7874 -0.4064)
			(end -0.7874 -0.4064)
			(stroke
				(width 0.1524)
				(type default)
			)
			(layer "B.SilkS")
		)
		(fp_line
			(start 0.7874 0.4064)
			(end 0.7874 -0.4064)
			(stroke
				(width 0.1524)
				(type default)
			)
			(layer "B.SilkS")
		)
		(fp_line
			(start -0.67945 -0.3048)
			(end -0.67945 0.3048)
			(stroke
				(width 0.1)
				(type default)
			)
			(layer "B.Fab")
		)
		(fp_line
			(start -0.67945 0.3048)
			(end -0.120396 0.3048)
			(stroke
				(width 0.1)
				(type default)
			)
			(layer "B.Fab")
		)
		(fp_line
			(start -0.12065 -0.3048)
			(end -0.67945 -0.3048)
			(stroke
				(width 0.1)
				(type default)
			)
			(layer "B.Fab")
		)
		(fp_line
			(start -0.12065 -0.2794)
			(end -0.12065 -0.3048)
			(stroke
				(width 0.1)
				(type default)
			)
			(layer "B.Fab")
		)
		(fp_line
			(start -0.120396 0.2794)
			(end 0.12065 0.2794)
			(stroke
				(width 0.1)
				(type default)
			)
			(layer "B.Fab")
		)
		(fp_line
			(start -0.120396 0.3048)
			(end -0.120396 0.2794)
			(stroke
				(width 0.1)
				(type default)
			)
			(layer "B.Fab")
		)
		(fp_line
			(start 0.12065 -0.305054)
			(end 0.12065 -0.2794)
			(stroke
				(width 0.1)
				(type default)
			)
			(layer "B.Fab")
		)
		(fp_line
			(start 0.12065 -0.2794)
			(end -0.12065 -0.2794)
			(stroke
				(width 0.1)
				(type default)
			)
			(layer "B.Fab")
		)
		(fp_line
			(start 0.12065 0.2794)
			(end 0.12065 0.3048)
			(stroke
				(width 0.1)
				(type default)
			)
			(layer "B.Fab")
		)
		(fp_line
			(start 0.12065 0.3048)
			(end 0.67945 0.3048)
			(stroke
				(width 0.1)
				(type default)
			)
			(layer "B.Fab")
		)
		(fp_line
			(start 0.67945 -0.305054)
			(end 0.12065 -0.305054)
			(stroke
				(width 0.1)
				(type default)
			)
			(layer "B.Fab")
		)
		(fp_line
			(start 0.67945 0.3048)
			(end 0.67945 -0.305054)
			(stroke
				(width 0.1)
				(type default)
			)
			(layer "B.Fab")
		)
		(pad "1" smd circle
			(at 0.40005 0 180)
			(size 0 0)
			(layers "B.Cu" "B.Mask" "B.Paste")
			(net "P3V3_AUX")
		)
		(pad "2" smd circle
			(at -0.40005 0 180)
			(size 0 0)
			(layers "B.Cu" "B.Mask" "B.Paste")
			(net "GND")
		)
	)
	(footprint ""
		(layer "B.Cu")
		(at 98.984054 -326.825102 -90)
		(property "Reference" "PC430_5"
			(at 0 0 90)
			(layer "B.SilkS")
			(hide yes)
			(effects
				(font
					(size 1.27 1.27)
				)
				(justify mirror)
			)
		)
		(property "Value" ""
			(at 0 0 90)
			(layer "B.Fab")
			(effects
				(font
					(size 1.27 1.27)
				)
				(justify mirror)
			)
		)
		(duplicate_pad_numbers_are_jumpers no)
		(fp_line
			(start -1.524 0.762)
			(end 1.524 0.762)
			(stroke
				(width 0.1524)
				(type default)
			)
			(layer "B.SilkS")
		)
		(fp_line
			(start 1.524 0.762)
			(end 1.524 -0.762)
			(stroke
				(width 0.1524)
				(type default)
			)
			(layer "B.SilkS")
		)
		(fp_line
			(start -1.524 -0.762)
			(end -1.524 0.762)
			(stroke
				(width 0.1524)
				(type default)
			)
			(layer "B.SilkS")
		)
		(fp_line
			(start 1.524 -0.762)
			(end -1.524 -0.762)
			(stroke
				(width 0.1524)
				(type default)
			)
			(layer "B.SilkS")
		)
		(fp_line
			(start -1.1049 0.724916)
			(end -1.1049 -0.724916)
			(stroke
				(width 0.1)
				(type default)
			)
			(layer "B.Fab")
		)
		(fp_line
			(start 1.1049 0.724916)
			(end -1.1049 0.724916)
			(stroke
				(width 0.1)
				(type default)
			)
			(layer "B.Fab")
		)
		(fp_line
			(start -1.1049 -0.724916)
			(end 1.1049 -0.724916)
			(stroke
				(width 0.1)
				(type default)
			)
			(layer "B.Fab")
		)
		(fp_line
			(start 1.1049 -0.724916)
			(end 1.1049 0.724916)
			(stroke
				(width 0.1)
				(type default)
			)
			(layer "B.Fab")
		)
		(pad "1" smd rect
			(at 0.889 0 270)
			(size 1.016 1.27)
			(layers "B.Cu" "B.Mask" "B.Paste")
			(net "PVDDCR_CPU1_P1")
		)
		(pad "2" smd rect
			(at -0.889 0 270)
			(size 1.016 1.27)
			(layers "B.Cu" "B.Mask" "B.Paste")
			(net "GND")
		)
	)
	(footprint ""
		(layer "B.Cu")
		(at 187.349384 -13.60043 -90)
		(property "Reference" "R6003"
			(at 0 0 90)
			(layer "B.SilkS")
			(hide yes)
			(effects
				(font
					(size 1.27 1.27)
				)
				(justify mirror)
			)
		)
		(property "Value" ""
			(at 0 0 90)
			(layer "B.Fab")
			(effects
				(font
					(size 1.27 1.27)
				)
				(justify mirror)
			)
		)
		(duplicate_pad_numbers_are_jumpers no)
		(fp_line
			(start -0.7874 0.4064)
			(end 0.7874 0.4064)
			(stroke
				(width 0.1524)
				(type default)
			)
			(layer "B.SilkS")
		)
		(fp_line
			(start 0.7874 0.4064)
			(end 0.7874 -0.4064)
			(stroke
				(width 0.1524)
				(type default)
			)
			(layer "B.SilkS")
		)
		(fp_line
			(start -0.7874 -0.4064)
			(end -0.7874 0.4064)
			(stroke
				(width 0.1524)
				(type default)
			)
			(layer "B.SilkS")
		)
		(fp_line
			(start 0.7874 -0.4064)
			(end -0.7874 -0.4064)
			(stroke
				(width 0.1524)
				(type default)
			)
			(layer "B.SilkS")
		)
		(fp_line
			(start -0.67945 0.3048)
			(end -0.120396 0.3048)
			(stroke
				(width 0.1)
				(type default)
			)
			(layer "B.Fab")
		)
		(fp_line
			(start -0.120396 0.3048)
			(end -0.120396 0.2794)
			(stroke
				(width 0.1)
				(type default)
			)
			(layer "B.Fab")
		)
		(fp_line
			(start 0.12065 0.3048)
			(end 0.67945 0.3048)
			(stroke
				(width 0.1)
				(type default)
			)
			(layer "B.Fab")
		)
		(fp_line
			(start 0.67945 0.3048)
			(end 0.67945 -0.305054)
			(stroke
				(width 0.1)
				(type default)
			)
			(layer "B.Fab")
		)
		(fp_line
			(start -0.120396 0.2794)
			(end 0.12065 0.2794)
			(stroke
				(width 0.1)
				(type default)
			)
			(layer "B.Fab")
		)
		(fp_line
			(start 0.12065 0.2794)
			(end 0.12065 0.3048)
			(stroke
				(width 0.1)
				(type default)
			)
			(layer "B.Fab")
		)
		(fp_line
			(start -0.12065 -0.2794)
			(end -0.12065 -0.3048)
			(stroke
				(width 0.1)
				(type default)
			)
			(layer "B.Fab")
		)
		(fp_line
			(start 0.12065 -0.2794)
			(end -0.12065 -0.2794)
			(stroke
				(width 0.1)
				(type default)
			)
			(layer "B.Fab")
		)
		(fp_line
			(start -0.67945 -0.3048)
			(end -0.67945 0.3048)
			(stroke
				(width 0.1)
				(type default)
			)
			(layer "B.Fab")
		)
		(fp_line
			(start -0.12065 -0.3048)
			(end -0.67945 -0.3048)
			(stroke
				(width 0.1)
				(type default)
			)
			(layer "B.Fab")
		)
		(fp_line
			(start 0.12065 -0.305054)
			(end 0.12065 -0.2794)
			(stroke
				(width 0.1)
				(type default)
			)
			(layer "B.Fab")
		)
		(fp_line
			(start 0.67945 -0.305054)
			(end 0.12065 -0.305054)
			(stroke
				(width 0.1)
				(type default)
			)
			(layer "B.Fab")
		)
		(pad "1" smd circle
			(at 0.40005 0 90)
			(size 0 0)
			(layers "B.Cu" "B.Mask" "B.Paste")
			(net "I3C_SCM_1_SDA")
		)
		(pad "2" smd circle
			(at -0.40005 0 90)
			(size 0 0)
			(layers "B.Cu" "B.Mask" "B.Paste")
			(net "I3C_SCM_1_R_SDA")
		)
	)
)
